(kicad_pcb
	(version 20260206)
	(generator "pcbnew")
	(generator_version "10.0")
	(general
		(thickness 1.6)
		(legacy_teardrops no)
	)
	(paper "A4")
	(title_block
		(title "baseboard — 13948-1b.1110WZS1818.brd")
		(comment 1 "Honey Badger (Wiwynn) / footprints 672-675 of 2523")
	)
	(layers
		(0 "F.Cu" signal "TOP")
		(4 "In1.Cu" signal "L2GND")
		(6 "In2.Cu" signal "L3")
		(8 "In3.Cu" signal "L4VCC")
		(10 "In4.Cu" signal "L5VCC")
		(12 "In5.Cu" signal "L6")
		(14 "In6.Cu" signal "L7GND")
		(2 "B.Cu" signal "BOTTOM")
		(9 "F.Adhes" user "F.Adhesive")
		(11 "B.Adhes" user "B.Adhesive")
		(13 "F.Paste" user "Package Geometry/Pastemask Top")
		(15 "B.Paste" user "Package Geometry/Pastemask Bottom")
		(5 "F.SilkS" user "Ref Des/Silkscreen Top")
		(7 "B.SilkS" user "Ref Des/Silkscreen Bottom")
		(1 "F.Mask" user "Board Geometry/Soldermask Top")
		(3 "B.Mask" user "Board Geometry/Soldermask Bottom")
		(17 "Dwgs.User" user "User.Drawings")
		(19 "Cmts.User" user "User.Comments")
		(21 "Eco1.User" user "User.Eco1")
		(23 "Eco2.User" user "User.Eco2")
		(25 "Edge.Cuts" user "Board Geometry/Outline")
		(27 "Margin" user)
		(31 "F.CrtYd" user "Package Geometry/Place Bound Top")
		(29 "B.CrtYd" user "Package Geometry/Place Bound Bottom")
		(35 "F.Fab" user "Ref Des/Assembly Top")
		(33 "B.Fab" user "Ref Des/Assembly Bottom")
	)
	(footprint ""
		(layer "F.Cu")
		(at 243.080032 -96.52 180)
		(property "Reference" "CN7"
			(at 0 0 180)
			(layer "F.SilkS")
			(hide yes)
			(effects
				(font
					(size 1.27 1.27)
				)
			)
		)
		(property "Value" "AMP-CONN10D-3-GP"
			(at 5.1562 -6.9469 180)
			(unlocked yes)
			(layer "F.Fab")
			(hide yes)
			(effects
				(font
					(size 1.016 1.016)
					(thickness 0.1524)
				)
			)
		)
		(property "Device Type" "G823MB10221KEU"
			(at 5.1562 -8.4709 180)
			(unlocked yes)
			(layer "F.Fab")
			(hide yes)
			(effects
				(font
					(size 1.016 1.016)
					(thickness 0.1524)
				)
			)
		)
		(duplicate_pad_numbers_are_jumpers no)
		(fp_line
			(start 6.5786 3.6576)
			(end 6.5786 -3.6576)
			(stroke
				(width 0.1524)
				(type default)
			)
			(layer "F.SilkS")
		)
		(fp_line
			(start 6.5786 -3.6576)
			(end -6.5786 -3.6576)
			(stroke
				(width 0.1524)
				(type default)
			)
			(layer "F.SilkS")
		)
		(fp_line
			(start 0.635 3.6576)
			(end 6.5786 3.6576)
			(stroke
				(width 0.1524)
				(type default)
			)
			(layer "F.SilkS")
		)
		(fp_line
			(start -0.7239 3.6576)
			(end -6.5786 3.6576)
			(stroke
				(width 0.1524)
				(type default)
			)
			(layer "F.SilkS")
		)
		(fp_line
			(start -3.6322 -3.7592)
			(end -3.6195 -3.7465)
			(stroke
				(width 0.3302)
				(type default)
			)
			(layer "F.SilkS")
		)
		(fp_line
			(start -4.3815 -3.7592)
			(end -3.6322 -3.7592)
			(stroke
				(width 0.3302)
				(type default)
			)
			(layer "F.SilkS")
		)
		(fp_line
			(start -6.5786 -3.6576)
			(end -6.5786 3.6576)
			(stroke
				(width 0.1524)
				(type default)
			)
			(layer "F.SilkS")
		)
		(fp_poly
			(pts
				(xy -3.999992 -3.7338) (xy -3.364992 -4.3688) (xy -4.634992 -4.3688)
			)
			(stroke
				(width 0)
				(type default)
			)
			(fill yes)
			(layer "F.SilkS")
		)
		(fp_poly
			(pts
				(xy -2.1844 0.70231) (xy 2.1971 0.70231) (xy 2.1971 -0.70231) (xy -2.1844 -0.70231)
			)
			(stroke
				(width 0)
				(type default)
			)
			(fill yes)
			(layer "F.SilkS")
		)
		(fp_rect
			(start -6.3246 3.1496)
			(end 6.3246 -3.1496)
			(stroke
				(width 0)
				(type default)
			)
			(fill no)
			(layer "F.CrtYd")
		)
		(fp_poly
			(pts
				(xy 6.8326 -3.1496) (xy -6.3246 -3.1496) (xy -6.3246 3.1496) (xy 6.3246 3.1496) (xy 6.3246 -3.1369)
				(xy 6.8326 -3.1369) (xy 6.8326 3.9116) (xy -6.8326 3.9116) (xy -6.8326 -3.9116) (xy 6.8326 -3.9116)
			)
			(stroke
				(width 0)
				(type default)
			)
			(fill no)
			(layer "F.CrtYd")
		)
		(fp_rect
			(start -6.8326 3.9116)
			(end 6.8326 -3.9116)
			(stroke
				(width 0)
				(type default)
			)
			(fill no)
			(layer "F.Fab")
		)
		(pad "" np_thru_hole circle
			(at -2.999994 0 180)
			(size 0.254 0.254)
			(drill 1.016)
			(layers "*.Cu" "*.Mask")
			(clearance 0.7366)
			(thermal_gap 0.7366)
		)
		(pad "" np_thru_hole circle
			(at 2.999994 0 180)
			(size 0.254 0.254)
			(drill 1.016)
			(layers "*.Cu" "*.Mask")
			(clearance 0.7366)
			(thermal_gap 0.7366)
		)
		(pad "1" smd rect
			(at -3.999992 -2.15011 180)
			(size 0.889 2.4892)
			(layers "F.Cu" "F.Mask" "F.Paste")
			(net "BMC_JTAG_L_EN")
		)
		(pad "2" smd rect
			(at -3.999992 2.15011 180)
			(size 0.889 2.4892)
			(layers "F.Cu" "F.Mask" "F.Paste")
			(net "JTAG_BMC_TCK")
		)
		(pad "3" smd rect
			(at -1.999996 -2.15011 180)
			(size 0.889 2.4892)
			(layers "F.Cu" "F.Mask" "F.Paste")
			(net "P3V3_STBY")
		)
		(pad "4" smd rect
			(at -1.999996 2.15011 180)
			(size 0.889 2.4892)
			(layers "F.Cu" "F.Mask" "F.Paste")
			(net "JTAG_IOC_TDO_L")
		)
		(pad "5" smd rect
			(at 0 -2.15011 180)
			(size 0.889 2.4892)
			(layers "F.Cu" "F.Mask" "F.Paste")
			(net "Net_257")
		)
		(pad "6" smd rect
			(at 0 2.15011 180)
			(size 0.889 2.4892)
			(layers "F.Cu" "F.Mask" "F.Paste")
			(net "JTAG_BMC_TMS")
		)
		(pad "7" smd rect
			(at 1.999996 -2.15011 180)
			(size 0.889 2.4892)
			(layers "F.Cu" "F.Mask" "F.Paste")
			(net "JTAG_BMC_TRST_N")
		)
		(pad "8" smd rect
			(at 1.999996 2.15011 180)
			(size 0.889 2.4892)
			(layers "F.Cu" "F.Mask" "F.Paste")
			(net "Net_256")
		)
		(pad "9" smd rect
			(at 3.999992 -2.15011 180)
			(size 0.889 2.4892)
			(layers "F.Cu" "F.Mask" "F.Paste")
			(net "GND")
		)
		(pad "10" smd rect
			(at 3.999992 2.15011 180)
			(size 0.889 2.4892)
			(layers "F.Cu" "F.Mask" "F.Paste")
			(net "JTAG_BMC_TDI")
		)
		(zone
			(layer "F.Cu")
			(hatch none 0.5)
			(connect_pads
				(clearance 0)
			)
			(min_thickness 0.25)
			(keepout
				(tracks allowed)
				(vias not_allowed)
				(pads allowed)
				(copperpour not_allowed)
				(footprints allowed)
			)
			(placement
				(enabled no)
				(sheetname "")
			)
			(fill
				(thermal_gap 0.5)
				(thermal_bridge_width 0.5)
				(island_removal_mode 0)
			)
			(polygon
				(pts
					(xy 239.270032 -97.42551) (xy 238.63554 -97.42551) (xy 238.63554 -96.91751) (xy 239.270032 -96.91751)
				)
			)
		)
		(zone
			(layer "F.Cu")
			(hatch none 0.5)
			(connect_pads
				(clearance 0)
			)
			(min_thickness 0.25)
			(keepout
				(tracks not_allowed)
				(vias allowed)
				(pads allowed)
				(copperpour not_allowed)
				(footprints allowed)
			)
			(placement
				(enabled no)
				(sheetname "")
			)
			(fill
				(thermal_gap 0.5)
				(thermal_bridge_width 0.5)
				(island_removal_mode 0)
			)
			(polygon
				(pts
					(xy 239.270032 -97.42551) (xy 238.63554 -97.42551) (xy 238.63554 -95.61449) (xy 239.270032 -95.61449)
				)
			)
		)
		(zone
			(layer "F.Cu")
			(hatch none 0.5)
			(connect_pads
				(clearance 0)
			)
			(min_thickness 0.25)
			(keepout
				(tracks allowed)
				(vias not_allowed)
				(pads allowed)
				(copperpour not_allowed)
				(footprints allowed)
			)
			(placement
				(enabled no)
				(sheetname "")
			)
			(fill
				(thermal_gap 0.5)
				(thermal_bridge_width 0.5)
				(island_removal_mode 0)
			)
			(polygon
				(pts
					(xy 239.270032 -97.42551) (xy 238.63554 -97.42551) (xy 238.63554 -95.61449) (xy 239.270032 -95.61449)
				)
			)
		)
		(zone
			(layer "F.Cu")
			(hatch none 0.5)
			(connect_pads
				(clearance 0)
			)
			(min_thickness 0.25)
			(keepout
				(tracks allowed)
				(vias not_allowed)
				(pads allowed)
				(copperpour not_allowed)
				(footprints allowed)
			)
			(placement
				(enabled no)
				(sheetname "")
			)
			(fill
				(thermal_gap 0.5)
				(thermal_bridge_width 0.5)
				(island_removal_mode 0)
			)
			(polygon
				(pts
					(xy 239.270032 -96.12249) (xy 238.63554 -96.12249) (xy 238.63554 -95.61449) (xy 239.270032 -95.61449)
				)
			)
		)
		(zone
			(layer "F.Cu")
			(hatch none 0.5)
			(connect_pads
				(clearance 0)
			)
			(min_thickness 0.25)
			(keepout
				(tracks allowed)
				(vias not_allowed)
				(pads allowed)
				(copperpour not_allowed)
				(footprints allowed)
			)
			(placement
				(enabled no)
				(sheetname "")
			)
			(fill
				(thermal_gap 0.5)
				(thermal_bridge_width 0.5)
				(island_removal_mode 0)
			)
			(polygon
				(pts
					(xy 245.264432 -97.42551) (xy 240.882932 -97.42551) (xy 240.882932 -96.91751) (xy 245.264432 -96.91751)
				)
			)
		)
		(zone
			(layer "F.Cu")
			(hatch none 0.5)
			(connect_pads
				(clearance 0)
			)
			(min_thickness 0.25)
			(keepout
				(tracks not_allowed)
				(vias allowed)
				(pads allowed)
				(copperpour not_allowed)
				(footprints allowed)
			)
			(placement
				(enabled no)
				(sheetname "")
			)
			(fill
				(thermal_gap 0.5)
				(thermal_bridge_width 0.5)
				(island_removal_mode 0)
			)
			(polygon
				(pts
					(xy 245.264432 -97.42551) (xy 240.882932 -97.42551) (xy 240.882932 -95.61449) (xy 245.264432 -95.61449)
				)
			)
		)
		(zone
			(layer "F.Cu")
			(hatch none 0.5)
			(connect_pads
				(clearance 0)
			)
			(min_thickness 0.25)
			(keepout
				(tracks allowed)
				(vias not_allowed)
				(pads allowed)
				(copperpour not_allowed)
				(footprints allowed)
			)
			(placement
				(enabled no)
				(sheetname "")
			)
			(fill
				(thermal_gap 0.5)
				(thermal_bridge_width 0.5)
				(island_removal_mode 0)
			)
			(polygon
				(pts
					(xy 245.264432 -97.42551) (xy 240.882932 -97.42551) (xy 240.882932 -95.61449) (xy 245.264432 -95.61449)
				)
			)
		)
		(zone
			(layer "F.Cu")
			(hatch none 0.5)
			(connect_pads
				(clearance 0)
			)
			(min_thickness 0.25)
			(keepout
				(tracks allowed)
				(vias not_allowed)
				(pads allowed)
				(copperpour not_allowed)
				(footprints allowed)
			)
			(placement
				(enabled no)
				(sheetname "")
			)
			(fill
				(thermal_gap 0.5)
				(thermal_bridge_width 0.5)
				(island_removal_mode 0)
			)
			(polygon
				(pts
					(xy 245.264432 -96.12249) (xy 240.882932 -96.12249) (xy 240.882932 -95.61449) (xy 245.264432 -95.61449)
				)
			)
		)
		(zone
			(layer "F.Cu")
			(hatch none 0.5)
			(connect_pads
				(clearance 0)
			)
			(min_thickness 0.25)
			(keepout
				(tracks allowed)
				(vias not_allowed)
				(pads allowed)
				(copperpour not_allowed)
				(footprints allowed)
			)
			(placement
				(enabled no)
				(sheetname "")
			)
			(fill
				(thermal_gap 0.5)
				(thermal_bridge_width 0.5)
				(island_removal_mode 0)
			)
			(polygon
				(pts
					(xy 247.524524 -97.42551) (xy 246.890032 -97.42551) (xy 246.890032 -96.91751) (xy 247.524524 -96.91751)
				)
			)
		)
		(zone
			(layer "F.Cu")
			(hatch none 0.5)
			(connect_pads
				(clearance 0)
			)
			(min_thickness 0.25)
			(keepout
				(tracks not_allowed)
				(vias allowed)
				(pads allowed)
				(copperpour not_allowed)
				(footprints allowed)
			)
			(placement
				(enabled no)
				(sheetname "")
			)
			(fill
				(thermal_gap 0.5)
				(thermal_bridge_width 0.5)
				(island_removal_mode 0)
			)
			(polygon
				(pts
					(xy 247.524524 -97.42551) (xy 246.890032 -97.42551) (xy 246.890032 -95.61449) (xy 247.524524 -95.61449)
				)
			)
		)
		(zone
			(layer "F.Cu")
			(hatch none 0.5)
			(connect_pads
				(clearance 0)
			)
			(min_thickness 0.25)
			(keepout
				(tracks allowed)
				(vias not_allowed)
				(pads allowed)
				(copperpour not_allowed)
				(footprints allowed)
			)
			(placement
				(enabled no)
				(sheetname "")
			)
			(fill
				(thermal_gap 0.5)
				(thermal_bridge_width 0.5)
				(island_removal_mode 0)
			)
			(polygon
				(pts
					(xy 247.524524 -97.42551) (xy 246.890032 -97.42551) (xy 246.890032 -95.61449) (xy 247.524524 -95.61449)
				)
			)
		)
		(zone
			(layer "F.Cu")
			(hatch none 0.5)
			(connect_pads
				(clearance 0)
			)
			(min_thickness 0.25)
			(keepout
				(tracks allowed)
				(vias not_allowed)
				(pads allowed)
				(copperpour not_allowed)
				(footprints allowed)
			)
			(placement
				(enabled no)
				(sheetname "")
			)
			(fill
				(thermal_gap 0.5)
				(thermal_bridge_width 0.5)
				(island_removal_mode 0)
			)
			(polygon
				(pts
					(xy 247.524524 -96.12249) (xy 246.890032 -96.12249) (xy 246.890032 -95.61449) (xy 247.524524 -95.61449)
				)
			)
		)
		(zone
			(layers "F.Cu" "B.Cu" "In1.Cu" "In2.Cu" "In3.Cu" "In4.Cu" "In5.Cu" "In6.Cu")
			(hatch none 0.5)
			(connect_pads
				(clearance 0)
			)
			(min_thickness 0.25)
			(keepout
				(tracks not_allowed)
				(vias allowed)
				(pads allowed)
				(copperpour not_allowed)
				(footprints allowed)
			)
			(placement
				(enabled no)
				(sheetname "")
			)
			(fill
				(thermal_gap 0.5)
				(thermal_bridge_width 0.5)
				(island_removal_mode 0)
			)
			(polygon
				(pts
					(arc
						(start 240.892838 -96.52)
						(mid 239.267238 -96.52)
						(end 240.892838 -96.52)
					)
				)
			)
		)
		(zone
			(layers "F.Cu" "B.Cu" "In1.Cu" "In2.Cu" "In3.Cu" "In4.Cu" "In5.Cu" "In6.Cu")
			(hatch none 0.5)
			(connect_pads
				(clearance 0)
			)
			(min_thickness 0.25)
			(keepout
				(tracks not_allowed)
				(vias allowed)
				(pads allowed)
				(copperpour not_allowed)
				(footprints allowed)
			)
			(placement
				(enabled no)
				(sheetname "")
			)
			(fill
				(thermal_gap 0.5)
				(thermal_bridge_width 0.5)
				(island_removal_mode 0)
			)
			(polygon
				(pts
					(arc
						(start 246.892826 -96.52)
						(mid 245.267226 -96.52)
						(end 246.892826 -96.52)
					)
				)
			)
		)
	)
	(footprint ""
		(layer "F.Cu")
		(at 79.888842 -126.284482 90)
		(property "Reference" "SC1100"
			(at 0 0 90)
			(layer "F.SilkS")
			(hide yes)
			(effects
				(font
					(size 1.27 1.27)
				)
			)
		)
		(property "Value" "SCD1U16V2KX-3GP"
			(at 1.1811 -2.7051 90)
			(unlocked yes)
			(layer "F.Fab")
			(hide yes)
			(effects
				(font
					(size 1.016 1.016)
					(thickness 0.1524)
				)
			)
		)
		(property "Device Type" "C402H22"
			(at 1.1811 -4.2291 90)
			(unlocked yes)
			(layer "F.Fab")
			(hide yes)
			(effects
				(font
					(size 1.016 1.016)
					(thickness 0.1524)
				)
			)
		)
		(duplicate_pad_numbers_are_jumpers no)
		(fp_rect
			(start -0.4318 0.9525)
			(end 0.4318 -0.9525)
			(stroke
				(width 0)
				(type default)
			)
			(fill no)
			(layer "F.CrtYd")
		)
		(fp_rect
			(start -0.4318 0.9525)
			(end 0.4318 -0.9525)
			(stroke
				(width 0)
				(type default)
			)
			(fill no)
			(layer "F.Fab")
		)
		(pad "1" smd custom
			(at 0 -0.4445 90)
			(size 0.1524 0.1524)
			(layers "F.Cu" "F.Mask" "F.Paste")
			(net "P1V8_E")
			(options
				(clearance outline)
				(anchor circle)
			)
			(primitives
				(gr_poly
					(pts
						(arc
							(start 0.3048 -0.2032)
							(mid 0.275042 -0.275042)
							(end 0.2032 -0.3048)
						)
						(arc
							(start -0.2032 -0.3048)
							(mid -0.275042 -0.275042)
							(end -0.3048 -0.2032)
						)
						(arc
							(start -0.3048 0.2032)
							(mid -0.275042 0.275042)
							(end -0.2032 0.3048)
						)
						(arc
							(start 0.2032 0.3048)
							(mid 0.275042 0.275042)
							(end 0.3048 0.2032)
						)
					)
					(width 0)
					(fill yes)
				)
			)
		)
		(pad "2" smd custom
			(at 0 0.4445 90)
			(size 0.1524 0.1524)
			(layers "F.Cu" "F.Mask" "F.Paste")
			(net "GND")
			(options
				(clearance outline)
				(anchor circle)
			)
			(primitives
				(gr_poly
					(pts
						(arc
							(start 0.3048 -0.2032)
							(mid 0.275042 -0.275042)
							(end 0.2032 -0.3048)
						)
						(arc
							(start -0.2032 -0.3048)
							(mid -0.275042 -0.275042)
							(end -0.3048 -0.2032)
						)
						(arc
							(start -0.3048 0.2032)
							(mid -0.275042 0.275042)
							(end -0.2032 0.3048)
						)
						(arc
							(start 0.2032 0.3048)
							(mid 0.275042 0.275042)
							(end 0.3048 0.2032)
						)
					)
					(width 0)
					(fill yes)
				)
			)
		)
	)
	(footprint ""
		(layer "F.Cu")
		(at 62.357 -215.265 90)
		(property "Reference" "R2102"
			(at 0 0 90)
			(layer "F.SilkS")
			(hide yes)
			(effects
				(font
					(size 1.27 1.27)
				)
			)
		)
		(property "Value" "26K1R2F-2-GP"
			(at 0.064008 -3.993896 90)
			(unlocked yes)
			(layer "F.Fab")
			(hide yes)
			(effects
				(font
					(size 1.016 1.016)
					(thickness 0.1524)
				)
			)
		)
		(property "Device Type" "R402H16"
			(at 0.064008 -5.517896 90)
			(unlocked yes)
			(layer "F.Fab")
			(hide yes)
			(effects
				(font
					(size 1.016 1.016)
					(thickness 0.1524)
				)
			)
		)
		(duplicate_pad_numbers_are_jumpers no)
		(fp_line
			(start 0.508 -0.9398)
			(end -0.508 -0.9398)
			(stroke
				(width 0.1524)
				(type default)
			)
			(layer "F.SilkS")
		)
		(fp_line
			(start -0.508 -0.9398)
			(end -0.508 0.9398)
			(stroke
				(width 0.1524)
				(type default)
			)
			(layer "F.SilkS")
		)
		(fp_rect
			(start -0.508 0.9398)
			(end 0.508 -0.9398)
			(stroke
				(width 0)
				(type default)
			)
			(fill no)
			(layer "F.CrtYd")
		)
		(fp_rect
			(start -0.508 0.9398)
			(end 0.508 -0.9398)
			(stroke
				(width 0)
				(type default)
			)
			(fill no)
			(layer "F.Fab")
		)
		(pad "1" smd custom
			(at 0 -0.4445 90)
			(size 0.1397 0.1397)
			(layers "F.Cu" "F.Mask" "F.Paste")
			(net "MB0_P12V_PWRGOOD")
			(options
				(clearance outline)
				(anchor circle)
			)
			(primitives
				(gr_poly
					(pts
						(arc
							(start -0.1778 -0.2794)
							(mid -0.249642 -0.249642)
							(end -0.2794 -0.1778)
						)
						(arc
							(start -0.2794 0.1778)
							(mid -0.249642 0.249642)
							(end -0.1778 0.2794)
						)
						(arc
							(start 0.1778 0.2794)
							(mid 0.249642 0.249642)
							(end 0.2794 0.1778)
						)
						(arc
							(start 0.2794 -0.1778)
							(mid 0.249642 -0.249642)
							(end 0.1778 -0.2794)
						)
					)
					(width 0)
					(fill yes)
				)
			)
		)
		(pad "2" smd custom
			(at 0 0.4445 90)
			(size 0.1397 0.1397)
			(layers "F.Cu" "F.Mask" "F.Paste")
			(net "AGND_CURRENT_MON")
			(options
				(clearance outline)
				(anchor circle)
			)
			(primitives
				(gr_poly
					(pts
						(arc
							(start -0.1778 -0.2794)
							(mid -0.249642 -0.249642)
							(end -0.2794 -0.1778)
						)
						(arc
							(start -0.2794 0.1778)
							(mid -0.249642 0.249642)
							(end -0.1778 0.2794)
						)
						(arc
							(start 0.1778 0.2794)
							(mid 0.249642 0.249642)
							(end 0.2794 0.1778)
						)
						(arc
							(start 0.2794 -0.1778)
							(mid 0.249642 -0.249642)
							(end 0.1778 -0.2794)
						)
					)
					(width 0)
					(fill yes)
				)
			)
		)
	)
	(footprint ""
		(layer "F.Cu")
		(at 192.278 -177.419 90)
		(property "Reference" "R479"
			(at 0 0 90)
			(layer "F.SilkS")
			(hide yes)
			(effects
				(font
					(size 1.27 1.27)
				)
			)
		)
		(property "Value" "51R2010F-GP"
			(at 0.254 -8.0772 90)
			(unlocked yes)
			(layer "F.Fab")
			(hide yes)
			(effects
				(font
					(size 1.016 1.016)
					(thickness 0.1524)
				)
			)
		)
		(property "Device Type" "R2010H28"
			(at 0.254 -9.6774 90)
			(unlocked yes)
			(layer "F.Fab")
			(hide yes)
			(effects
				(font
					(size 1.016 1.016)
					(thickness 0.1524)
				)
			)
		)
		(duplicate_pad_numbers_are_jumpers no)
		(fp_line
			(start 1.651 -3.302)
			(end -1.651 -3.302)
			(stroke
				(width 0.1524)
				(type default)
			)
			(layer "F.SilkS")
		)
		(fp_line
			(start -1.651 -3.302)
			(end -1.651 3.302)
			(stroke
				(width 0.1524)
				(type default)
			)
			(layer "F.SilkS")
		)
		(fp_line
			(start 1.651 3.302)
			(end 1.651 -3.302)
			(stroke
				(width 0.1524)
				(type default)
			)
			(layer "F.SilkS")
		)
		(fp_line
			(start -1.651 3.302)
			(end 1.651 3.302)
			(stroke
				(width 0.1524)
				(type default)
			)
			(layer "F.SilkS")
		)
		(fp_rect
			(start -1.7272 -3.3782)
			(end 1.7272 3.3782)
			(stroke
				(width 0)
				(type default)
			)
			(fill no)
			(layer "F.CrtYd")
		)
		(fp_poly
			(pts
				(xy 1.7272 3.3782) (xy 1.7272 -3.3782) (xy -1.7272 -3.3782) (xy -1.7272 3.3782)
			)
			(stroke
				(width 0)
				(type default)
			)
			(fill no)
			(layer "F.Fab")
		)
		(pad "1" smd rect
			(at 0 -2.3495 90)
			(size 2.794 1.143)
			(layers "F.Cu" "F.Mask" "F.Paste")
			(net "P3V3_STBY")
		)
		(pad "2" smd rect
			(at 0 2.3495 90)
			(size 2.794 1.143)
			(layers "F.Cu" "F.Mask" "F.Paste")
			(net "HB_OUT")
		)
	)
)
